# T6G (Grand Teton) — schematic netlist excerpt (pin names and nets, part order shuffled) for the footprints in the layout excerpt that follows; sources: Cadence DE-HDL packaged netlist, KiCad conversion of 04192023_DAF0TMB3IC0_F0TG_MB_C_brd_V02_OCP.brd

R225  Q_RES  33 5% CHIP  pkg 0402LF  page 192 : A = PWRGD_PVDD33_S5 ; B = FM_PWRGD_PVDD33_S5
R3466  Q_RES  10K 1% CHIP  pkg 0402LF  page 128 : A = RST_PERST_1_SWB_BUF_R_N ; B = GND
R669  Q_RES  33.2 1% CHIP  pkg 0201LF  page 278 : A = SMB_RT_CPU0_P0_ROM_R_SDA ; B = SMB_RT_CPU0_P0_ROM_SDA

(kicad_pcb
	(version 20260206)
	(generator "pcbnew")
	(generator_version "10.0")
	(general
		(thickness 1.6)
		(legacy_teardrops no)
	)
	(paper "A4")
	(title_block
		(title "04192023_DAF0TMB3IC0_F0TG_MB_C_brd_V02_OCP.brd")
		(comment 1 "Grand Teton / footprints 3301-3303 of 8354")
	)
	(layers
		(0 "F.Cu" signal "TOP")
		(4 "In1.Cu" signal "GND")
		(6 "In2.Cu" signal "IN1")
		(8 "In3.Cu" signal "GND1")
		(10 "In4.Cu" signal "IN2")
		(12 "In5.Cu" signal "GND2")
		(14 "In6.Cu" signal "IN3")
		(16 "In7.Cu" signal "GND3")
		(18 "In8.Cu" signal "VCC")
		(20 "In9.Cu" signal "VCC1")
		(22 "In10.Cu" signal "GND4")
		(24 "In11.Cu" signal "IN4")
		(26 "In12.Cu" signal "GND5")
		(28 "In13.Cu" signal "IN5")
		(30 "In14.Cu" signal "GND6")
		(32 "In15.Cu" signal "IN6")
		(34 "In16.Cu" signal "GND7")
		(2 "B.Cu" signal "BOTTOM")
		(9 "F.Adhes" user "F.Adhesive")
		(11 "B.Adhes" user "B.Adhesive")
		(13 "F.Paste" user "Package Geometry/Pastemask Top")
		(15 "B.Paste" user "Package Geometry/Pastemask Bottom")
		(5 "F.SilkS" user "Ref Des/Silkscreen Top")
		(7 "B.SilkS" user "Ref Des/Silkscreen Bottom")
		(1 "F.Mask" user "Board Geometry/Soldermask Top")
		(3 "B.Mask" user "Board Geometry/Soldermask Bottom")
		(17 "Dwgs.User" user "User.Drawings")
		(19 "Cmts.User" user "User.Comments")
		(21 "Eco1.User" user "User.Eco1")
		(23 "Eco2.User" user "User.Eco2")
		(25 "Edge.Cuts" user "Board Geometry/Outline")
		(27 "Margin" user)
		(31 "F.CrtYd" user "Package Geometry/Place Bound Top")
		(29 "B.CrtYd" user "Package Geometry/Place Bound Bottom")
		(35 "F.Fab" user "Ref Des/Assembly Top")
		(33 "B.Fab" user "Ref Des/Assembly Bottom")
	)
	(footprint ""
		(layer "F.Cu")
		(at 197.269608 -107.529376 180)
		(property "Reference" "R225"
			(at 0 0 180)
			(layer "F.SilkS")
			(hide yes)
			(effects
				(font
					(size 1.27 1.27)
				)
			)
		)
		(property "Value" ""
			(at 0 0 180)
			(layer "F.Fab")
			(effects
				(font
					(size 1.27 1.27)
				)
			)
		)
		(duplicate_pad_numbers_are_jumpers no)
		(fp_line
			(start 0.7874 0.4064)
			(end -0.7874 0.4064)
			(stroke
				(width 0.1524)
				(type default)
			)
			(layer "F.SilkS")
		)
		(fp_line
			(start 0.7874 -0.4064)
			(end 0.7874 0.4064)
			(stroke
				(width 0.1524)
				(type default)
			)
			(layer "F.SilkS")
		)
		(fp_line
			(start -0.7874 0.4064)
			(end -0.7874 -0.4064)
			(stroke
				(width 0.1524)
				(type default)
			)
			(layer "F.SilkS")
		)
		(fp_line
			(start -0.7874 -0.4064)
			(end 0.7874 -0.4064)
			(stroke
				(width 0.1524)
				(type default)
			)
			(layer "F.SilkS")
		)
		(fp_line
			(start 0.67945 0.3048)
			(end 0.120396 0.3048)
			(stroke
				(width 0.1)
				(type default)
			)
			(layer "F.Fab")
		)
		(fp_line
			(start 0.67945 -0.3048)
			(end 0.67945 0.3048)
			(stroke
				(width 0.1)
				(type default)
			)
			(layer "F.Fab")
		)
		(fp_line
			(start 0.12065 -0.2794)
			(end 0.12065 -0.3048)
			(stroke
				(width 0.1)
				(type default)
			)
			(layer "F.Fab")
		)
		(fp_line
			(start 0.12065 -0.3048)
			(end 0.67945 -0.3048)
			(stroke
				(width 0.1)
				(type default)
			)
			(layer "F.Fab")
		)
		(fp_line
			(start 0.120396 0.3048)
			(end 0.120396 0.2794)
			(stroke
				(width 0.1)
				(type default)
			)
			(layer "F.Fab")
		)
		(fp_line
			(start 0.120396 0.2794)
			(end -0.12065 0.2794)
			(stroke
				(width 0.1)
				(type default)
			)
			(layer "F.Fab")
		)
		(fp_line
			(start -0.12065 0.3048)
			(end -0.67945 0.3048)
			(stroke
				(width 0.1)
				(type default)
			)
			(layer "F.Fab")
		)
		(fp_line
			(start -0.12065 0.2794)
			(end -0.12065 0.3048)
			(stroke
				(width 0.1)
				(type default)
			)
			(layer "F.Fab")
		)
		(fp_line
			(start -0.12065 -0.2794)
			(end 0.12065 -0.2794)
			(stroke
				(width 0.1)
				(type default)
			)
			(layer "F.Fab")
		)
		(fp_line
			(start -0.12065 -0.305054)
			(end -0.12065 -0.2794)
			(stroke
				(width 0.1)
				(type default)
			)
			(layer "F.Fab")
		)
		(fp_line
			(start -0.67945 0.3048)
			(end -0.67945 -0.305054)
			(stroke
				(width 0.1)
				(type default)
			)
			(layer "F.Fab")
		)
		(fp_line
			(start -0.67945 -0.305054)
			(end -0.12065 -0.305054)
			(stroke
				(width 0.1)
				(type default)
			)
			(layer "F.Fab")
		)
		(pad "1" smd circle
			(at -0.40005 0 180)
			(size 0 0)
			(layers "F.Cu" "F.Mask" "F.Paste")
			(net "PWRGD_PVDD33_S5")
		)
		(pad "2" smd circle
			(at 0.40005 0 180)
			(size 0 0)
			(layers "F.Cu" "F.Mask" "F.Paste")
			(net "FM_PWRGD_PVDD33_S5")
		)
	)
	(footprint ""
		(layer "F.Cu")
		(at 39.95801 -438.531 180)
		(property "Reference" "R3466"
			(at 0 0 180)
			(layer "F.SilkS")
			(hide yes)
			(effects
				(font
					(size 1.27 1.27)
				)
			)
		)
		(property "Value" ""
			(at 0 0 180)
			(layer "F.Fab")
			(effects
				(font
					(size 1.27 1.27)
				)
			)
		)
		(duplicate_pad_numbers_are_jumpers no)
		(fp_line
			(start 0.7874 0.4064)
			(end -0.7874 0.4064)
			(stroke
				(width 0.1524)
				(type default)
			)
			(layer "F.SilkS")
		)
		(fp_line
			(start 0.7874 -0.4064)
			(end 0.7874 0.4064)
			(stroke
				(width 0.1524)
				(type default)
			)
			(layer "F.SilkS")
		)
		(fp_line
			(start -0.7874 0.4064)
			(end -0.7874 -0.4064)
			(stroke
				(width 0.1524)
				(type default)
			)
			(layer "F.SilkS")
		)
		(fp_line
			(start -0.7874 -0.4064)
			(end 0.7874 -0.4064)
			(stroke
				(width 0.1524)
				(type default)
			)
			(layer "F.SilkS")
		)
		(fp_line
			(start 0.67945 0.3048)
			(end 0.120396 0.3048)
			(stroke
				(width 0.1)
				(type default)
			)
			(layer "F.Fab")
		)
		(fp_line
			(start 0.67945 -0.3048)
			(end 0.67945 0.3048)
			(stroke
				(width 0.1)
				(type default)
			)
			(layer "F.Fab")
		)
		(fp_line
			(start 0.12065 -0.2794)
			(end 0.12065 -0.3048)
			(stroke
				(width 0.1)
				(type default)
			)
			(layer "F.Fab")
		)
		(fp_line
			(start 0.12065 -0.3048)
			(end 0.67945 -0.3048)
			(stroke
				(width 0.1)
				(type default)
			)
			(layer "F.Fab")
		)
		(fp_line
			(start 0.120396 0.3048)
			(end 0.120396 0.2794)
			(stroke
				(width 0.1)
				(type default)
			)
			(layer "F.Fab")
		)
		(fp_line
			(start 0.120396 0.2794)
			(end -0.12065 0.2794)
			(stroke
				(width 0.1)
				(type default)
			)
			(layer "F.Fab")
		)
		(fp_line
			(start -0.12065 0.3048)
			(end -0.67945 0.3048)
			(stroke
				(width 0.1)
				(type default)
			)
			(layer "F.Fab")
		)
		(fp_line
			(start -0.12065 0.2794)
			(end -0.12065 0.3048)
			(stroke
				(width 0.1)
				(type default)
			)
			(layer "F.Fab")
		)
		(fp_line
			(start -0.12065 -0.2794)
			(end 0.12065 -0.2794)
			(stroke
				(width 0.1)
				(type default)
			)
			(layer "F.Fab")
		)
		(fp_line
			(start -0.12065 -0.305054)
			(end -0.12065 -0.2794)
			(stroke
				(width 0.1)
				(type default)
			)
			(layer "F.Fab")
		)
		(fp_line
			(start -0.67945 0.3048)
			(end -0.67945 -0.305054)
			(stroke
				(width 0.1)
				(type default)
			)
			(layer "F.Fab")
		)
		(fp_line
			(start -0.67945 -0.305054)
			(end -0.12065 -0.305054)
			(stroke
				(width 0.1)
				(type default)
			)
			(layer "F.Fab")
		)
		(pad "1" smd circle
			(at -0.40005 0 180)
			(size 0 0)
			(layers "F.Cu" "F.Mask" "F.Paste")
			(net "RST_PERST_1_SWB_BUF_R_N")
		)
		(pad "2" smd circle
			(at 0.40005 0 180)
			(size 0 0)
			(layers "F.Cu" "F.Mask" "F.Paste")
			(net "GND")
		)
	)
	(footprint ""
		(layer "F.Cu")
		(at 295.576752 -422.173908 90)
		(property "Reference" "R669"
			(at 0 0 90)
			(layer "F.SilkS")
			(hide yes)
			(effects
				(font
					(size 1.27 1.27)
				)
			)
		)
		(property "Value" ""
			(at 0 0 90)
			(layer "F.Fab")
			(effects
				(font
					(size 1.27 1.27)
				)
			)
		)
		(duplicate_pad_numbers_are_jumpers no)
		(fp_line
			(start 0.32512 -0.175006)
			(end 0.32512 0.175006)
			(stroke
				(width 0.1)
				(type default)
			)
			(layer "F.Fab")
		)
		(fp_line
			(start -0.32512 -0.175006)
			(end 0.32512 -0.175006)
			(stroke
				(width 0.1)
				(type default)
			)
			(layer "F.Fab")
		)
		(fp_line
			(start 0.32512 0.175006)
			(end -0.32512 0.175006)
			(stroke
				(width 0.1)
				(type default)
			)
			(layer "F.Fab")
		)
		(fp_line
			(start -0.32512 0.175006)
			(end -0.32512 -0.175006)
			(stroke
				(width 0.1)
				(type default)
			)
			(layer "F.Fab")
		)
		(pad "1" smd rect
			(at -0.2667 0 90)
			(size 0.3048 0.381)
			(layers "F.Cu" "F.Mask" "F.Paste")
			(net "SMB_RT_CPU0_P0_ROM_R_SDA")
		)
		(pad "2" smd rect
			(at 0.2667 0 270)
			(size 0.3048 0.381)
			(layers "F.Cu" "F.Mask" "F.Paste")
			(net "SMB_RT_CPU0_P0_ROM_SDA")
		)
	)
)
